# T6G (Grand Teton) — schematic netlist excerpt (pin names and nets, part order shuffled) for the footprints in the layout excerpt that follows; sources: Cadence DE-HDL packaged netlist, KiCad conversion of 04192023_DAF0TMB3IC0_F0TG_MB_C_brd_V02_OCP.brd

C500  Q_CAP  0.1UF 10V 10% X7S  pkg C0201  page 356 : A = P0V9_CPU1_RT3_2A ; B = GND
PR3911  Q_RES  0 5% CHIP  pkg 0402LF  page 263 : A = HSC_VDD_R_2 ; B = HSC_VDD
C2560  Q_CAP  22UF 4V 20% X6S  pkg C0402  page 70 : A = PVDDCR_SOC_P0 ; B = GND

(kicad_pcb
	(version 20260206)
	(generator "pcbnew")
	(generator_version "10.0")
	(general
		(thickness 1.6)
		(legacy_teardrops no)
	)
	(paper "A4")
	(title_block
		(title "04192023_DAF0TMB3IC0_F0TG_MB_C_brd_V02_OCP.brd")
		(comment 1 "Grand Teton / footprints 7622-7624 of 8354")
	)
	(layers
		(0 "F.Cu" signal "TOP")
		(4 "In1.Cu" signal "GND")
		(6 "In2.Cu" signal "IN1")
		(8 "In3.Cu" signal "GND1")
		(10 "In4.Cu" signal "IN2")
		(12 "In5.Cu" signal "GND2")
		(14 "In6.Cu" signal "IN3")
		(16 "In7.Cu" signal "GND3")
		(18 "In8.Cu" signal "VCC")
		(20 "In9.Cu" signal "VCC1")
		(22 "In10.Cu" signal "GND4")
		(24 "In11.Cu" signal "IN4")
		(26 "In12.Cu" signal "GND5")
		(28 "In13.Cu" signal "IN5")
		(30 "In14.Cu" signal "GND6")
		(32 "In15.Cu" signal "IN6")
		(34 "In16.Cu" signal "GND7")
		(2 "B.Cu" signal "BOTTOM")
		(9 "F.Adhes" user "F.Adhesive")
		(11 "B.Adhes" user "B.Adhesive")
		(13 "F.Paste" user "Package Geometry/Pastemask Top")
		(15 "B.Paste" user "Package Geometry/Pastemask Bottom")
		(5 "F.SilkS" user "Ref Des/Silkscreen Top")
		(7 "B.SilkS" user "Ref Des/Silkscreen Bottom")
		(1 "F.Mask" user "Board Geometry/Soldermask Top")
		(3 "B.Mask" user "Board Geometry/Soldermask Bottom")
		(17 "Dwgs.User" user "User.Drawings")
		(19 "Cmts.User" user "User.Comments")
		(21 "Eco1.User" user "User.Eco1")
		(23 "Eco2.User" user "User.Eco2")
		(25 "Edge.Cuts" user "Board Geometry/Outline")
		(27 "Margin" user)
		(31 "F.CrtYd" user "Package Geometry/Place Bound Top")
		(29 "B.CrtYd" user "Package Geometry/Place Bound Bottom")
		(35 "F.Fab" user "Ref Des/Assembly Top")
		(33 "B.Fab" user "Ref Des/Assembly Bottom")
	)
	(footprint ""
		(layer "B.Cu")
		(at 349.834454 -255.84531)
		(property "Reference" "C2560"
			(at 0 0 0)
			(layer "B.SilkS")
			(hide yes)
			(effects
				(font
					(size 1.27 1.27)
				)
				(justify mirror)
			)
		)
		(property "Value" ""
			(at 0 0 0)
			(layer "B.Fab")
			(effects
				(font
					(size 1.27 1.27)
				)
				(justify mirror)
			)
		)
		(duplicate_pad_numbers_are_jumpers no)
		(fp_line
			(start -0.7874 -0.4064)
			(end -0.7874 0.4064)
			(stroke
				(width 0.1524)
				(type default)
			)
			(layer "B.SilkS")
		)
		(fp_line
			(start -0.7874 0.4064)
			(end 0.7874 0.4064)
			(stroke
				(width 0.1524)
				(type default)
			)
			(layer "B.SilkS")
		)
		(fp_line
			(start 0.7874 -0.4064)
			(end -0.7874 -0.4064)
			(stroke
				(width 0.1524)
				(type default)
			)
			(layer "B.SilkS")
		)
		(fp_line
			(start 0.7874 0.4064)
			(end 0.7874 -0.4064)
			(stroke
				(width 0.1524)
				(type default)
			)
			(layer "B.SilkS")
		)
		(fp_line
			(start -0.67945 -0.3048)
			(end -0.67945 0.3048)
			(stroke
				(width 0.1)
				(type default)
			)
			(layer "B.Fab")
		)
		(fp_line
			(start -0.67945 0.3048)
			(end -0.120396 0.3048)
			(stroke
				(width 0.1)
				(type default)
			)
			(layer "B.Fab")
		)
		(fp_line
			(start -0.12065 -0.3048)
			(end -0.67945 -0.3048)
			(stroke
				(width 0.1)
				(type default)
			)
			(layer "B.Fab")
		)
		(fp_line
			(start -0.12065 -0.2794)
			(end -0.12065 -0.3048)
			(stroke
				(width 0.1)
				(type default)
			)
			(layer "B.Fab")
		)
		(fp_line
			(start -0.120396 0.2794)
			(end 0.12065 0.2794)
			(stroke
				(width 0.1)
				(type default)
			)
			(layer "B.Fab")
		)
		(fp_line
			(start -0.120396 0.3048)
			(end -0.120396 0.2794)
			(stroke
				(width 0.1)
				(type default)
			)
			(layer "B.Fab")
		)
		(fp_line
			(start 0.12065 -0.305054)
			(end 0.12065 -0.2794)
			(stroke
				(width 0.1)
				(type default)
			)
			(layer "B.Fab")
		)
		(fp_line
			(start 0.12065 -0.2794)
			(end -0.12065 -0.2794)
			(stroke
				(width 0.1)
				(type default)
			)
			(layer "B.Fab")
		)
		(fp_line
			(start 0.12065 0.2794)
			(end 0.12065 0.3048)
			(stroke
				(width 0.1)
				(type default)
			)
			(layer "B.Fab")
		)
		(fp_line
			(start 0.12065 0.3048)
			(end 0.67945 0.3048)
			(stroke
				(width 0.1)
				(type default)
			)
			(layer "B.Fab")
		)
		(fp_line
			(start 0.67945 -0.305054)
			(end 0.12065 -0.305054)
			(stroke
				(width 0.1)
				(type default)
			)
			(layer "B.Fab")
		)
		(fp_line
			(start 0.67945 0.3048)
			(end 0.67945 -0.305054)
			(stroke
				(width 0.1)
				(type default)
			)
			(layer "B.Fab")
		)
		(pad "1" smd circle
			(at 0.40005 0 180)
			(size 0 0)
			(layers "B.Cu" "B.Mask" "B.Paste")
			(net "PVDDCR_SOC_P0")
		)
		(pad "2" smd circle
			(at -0.40005 0 180)
			(size 0 0)
			(layers "B.Cu" "B.Mask" "B.Paste")
			(net "GND")
		)
	)
	(footprint ""
		(layer "B.Cu")
		(at 204.5843 -402.744432 -90)
		(property "Reference" "PR3911"
			(at 0 0 90)
			(layer "B.SilkS")
			(hide yes)
			(effects
				(font
					(size 1.27 1.27)
				)
				(justify mirror)
			)
		)
		(property "Value" ""
			(at 0 0 90)
			(layer "B.Fab")
			(effects
				(font
					(size 1.27 1.27)
				)
				(justify mirror)
			)
		)
		(duplicate_pad_numbers_are_jumpers no)
		(fp_line
			(start -0.7874 0.4064)
			(end 0.7874 0.4064)
			(stroke
				(width 0.1524)
				(type default)
			)
			(layer "B.SilkS")
		)
		(fp_line
			(start 0.7874 0.4064)
			(end 0.7874 -0.4064)
			(stroke
				(width 0.1524)
				(type default)
			)
			(layer "B.SilkS")
		)
		(fp_line
			(start -0.7874 -0.4064)
			(end -0.7874 0.4064)
			(stroke
				(width 0.1524)
				(type default)
			)
			(layer "B.SilkS")
		)
		(fp_line
			(start 0.7874 -0.4064)
			(end -0.7874 -0.4064)
			(stroke
				(width 0.1524)
				(type default)
			)
			(layer "B.SilkS")
		)
		(fp_line
			(start -0.67945 0.3048)
			(end -0.120396 0.3048)
			(stroke
				(width 0.1)
				(type default)
			)
			(layer "B.Fab")
		)
		(fp_line
			(start -0.120396 0.3048)
			(end -0.120396 0.2794)
			(stroke
				(width 0.1)
				(type default)
			)
			(layer "B.Fab")
		)
		(fp_line
			(start 0.12065 0.3048)
			(end 0.67945 0.3048)
			(stroke
				(width 0.1)
				(type default)
			)
			(layer "B.Fab")
		)
		(fp_line
			(start 0.67945 0.3048)
			(end 0.67945 -0.305054)
			(stroke
				(width 0.1)
				(type default)
			)
			(layer "B.Fab")
		)
		(fp_line
			(start -0.120396 0.2794)
			(end 0.12065 0.2794)
			(stroke
				(width 0.1)
				(type default)
			)
			(layer "B.Fab")
		)
		(fp_line
			(start 0.12065 0.2794)
			(end 0.12065 0.3048)
			(stroke
				(width 0.1)
				(type default)
			)
			(layer "B.Fab")
		)
		(fp_line
			(start -0.12065 -0.2794)
			(end -0.12065 -0.3048)
			(stroke
				(width 0.1)
				(type default)
			)
			(layer "B.Fab")
		)
		(fp_line
			(start 0.12065 -0.2794)
			(end -0.12065 -0.2794)
			(stroke
				(width 0.1)
				(type default)
			)
			(layer "B.Fab")
		)
		(fp_line
			(start -0.67945 -0.3048)
			(end -0.67945 0.3048)
			(stroke
				(width 0.1)
				(type default)
			)
			(layer "B.Fab")
		)
		(fp_line
			(start -0.12065 -0.3048)
			(end -0.67945 -0.3048)
			(stroke
				(width 0.1)
				(type default)
			)
			(layer "B.Fab")
		)
		(fp_line
			(start 0.12065 -0.305054)
			(end 0.12065 -0.2794)
			(stroke
				(width 0.1)
				(type default)
			)
			(layer "B.Fab")
		)
		(fp_line
			(start 0.67945 -0.305054)
			(end 0.12065 -0.305054)
			(stroke
				(width 0.1)
				(type default)
			)
			(layer "B.Fab")
		)
		(pad "1" smd circle
			(at 0.40005 0 90)
			(size 0 0)
			(layers "B.Cu" "B.Mask" "B.Paste")
			(net "HSC_VDD_R_2")
		)
		(pad "2" smd circle
			(at -0.40005 0 90)
			(size 0 0)
			(layers "B.Cu" "B.Mask" "B.Paste")
			(net "HSC_VDD")
		)
	)
	(footprint ""
		(layer "B.Cu")
		(at 114.618516 -388.011162 -90)
		(property "Reference" "C500"
			(at 0 0 90)
			(layer "B.SilkS")
			(hide yes)
			(effects
				(font
					(size 1.27 1.27)
				)
				(justify mirror)
			)
		)
		(property "Value" ""
			(at 0 0 90)
			(layer "B.Fab")
			(effects
				(font
					(size 1.27 1.27)
				)
				(justify mirror)
			)
		)
		(duplicate_pad_numbers_are_jumpers no)
		(fp_line
			(start -0.299974 0.150114)
			(end 0.299974 0.150114)
			(stroke
				(width 0.1)
				(type default)
			)
			(layer "B.Fab")
		)
		(fp_line
			(start 0.299974 0.150114)
			(end 0.299974 -0.150114)
			(stroke
				(width 0.1)
				(type default)
			)
			(layer "B.Fab")
		)
		(fp_line
			(start -0.299974 -0.150114)
			(end -0.299974 0.150114)
			(stroke
				(width 0.1)
				(type default)
			)
			(layer "B.Fab")
		)
		(fp_line
			(start 0.299974 -0.150114)
			(end -0.299974 -0.150114)
			(stroke
				(width 0.1)
				(type default)
			)
			(layer "B.Fab")
		)
		(pad "1" smd rect
			(at 0.2667 0 90)
			(size 0.3048 0.381)
			(layers "B.Cu" "B.Mask" "B.Paste")
			(net "P0V9_CPU1_RT3_2A")
		)
		(pad "2" smd rect
			(at -0.2667 0 90)
			(size 0.3048 0.381)
			(layers "B.Cu" "B.Mask" "B.Paste")
			(net "GND")
		)
	)
)
